(kicad_pcb
	(version 20260206)
	(generator "pcbnew")
	(generator_version "10.0")
	(general
		(thickness 1.6)
		(legacy_teardrops no)
	)
	(paper "A4")
	(title_block
		(title "01162023_DA0F0TEBIF0_F0T_Expander_BD_F_brd_V02_OCP.brd")
		(comment 1 "Grand Teton / footprints 4051-4055 of 9728")
	)
	(layers
		(0 "F.Cu" signal "TOP")
		(4 "In1.Cu" signal "GND")
		(6 "In2.Cu" signal "VCC")
		(8 "In3.Cu" signal "VCC1")
		(10 "In4.Cu" signal "GND1")
		(12 "In5.Cu" signal "IN1")
		(14 "In6.Cu" signal "GND2")
		(16 "In7.Cu" signal "IN2")
		(18 "In8.Cu" signal "GND3")
		(20 "In9.Cu" signal "IN3")
		(22 "In10.Cu" signal "GND4")
		(24 "In11.Cu" signal "IN4")
		(26 "In12.Cu" signal "GND5")
		(28 "In13.Cu" signal "IN5")
		(30 "In14.Cu" signal "GND6")
		(32 "In15.Cu" signal "IN6")
		(34 "In16.Cu" signal "GND7")
		(2 "B.Cu" signal "BOTTOM")
		(9 "F.Adhes" user "F.Adhesive")
		(11 "B.Adhes" user "B.Adhesive")
		(13 "F.Paste" user "Package Geometry/Pastemask Top")
		(15 "B.Paste" user "Package Geometry/Pastemask Bottom")
		(5 "F.SilkS" user "Ref Des/Silkscreen Top")
		(7 "B.SilkS" user "Ref Des/Silkscreen Bottom")
		(1 "F.Mask" user "Board Geometry/Soldermask Top")
		(3 "B.Mask" user "Board Geometry/Soldermask Bottom")
		(17 "Dwgs.User" user "User.Drawings")
		(19 "Cmts.User" user "User.Comments")
		(21 "Eco1.User" user "User.Eco1")
		(23 "Eco2.User" user "User.Eco2")
		(25 "Edge.Cuts" user "Board Geometry/Outline")
		(27 "Margin" user)
		(31 "F.CrtYd" user "Package Geometry/Place Bound Top")
		(29 "B.CrtYd" user "Package Geometry/Place Bound Bottom")
		(35 "F.Fab" user "Ref Des/Assembly Top")
		(33 "B.Fab" user "Ref Des/Assembly Bottom")
	)
	(footprint ""
		(layer "F.Cu")
		(at 403.175216 -64.102234 180)
		(property "Reference" "PR7097"
			(at 0 0 180)
			(layer "F.SilkS")
			(hide yes)
			(effects
				(font
					(size 1.27 1.27)
				)
			)
		)
		(property "Value" ""
			(at 0 0 180)
			(layer "F.Fab")
			(effects
				(font
					(size 1.27 1.27)
				)
			)
		)
		(duplicate_pad_numbers_are_jumpers no)
		(fp_line
			(start 0.7874 0.4064)
			(end -0.7874 0.4064)
			(stroke
				(width 0.1524)
				(type default)
			)
			(layer "F.SilkS")
		)
		(fp_line
			(start 0.7874 -0.4064)
			(end 0.7874 0.4064)
			(stroke
				(width 0.1524)
				(type default)
			)
			(layer "F.SilkS")
		)
		(fp_line
			(start -0.7874 0.4064)
			(end -0.7874 -0.4064)
			(stroke
				(width 0.1524)
				(type default)
			)
			(layer "F.SilkS")
		)
		(fp_line
			(start -0.7874 -0.4064)
			(end 0.7874 -0.4064)
			(stroke
				(width 0.1524)
				(type default)
			)
			(layer "F.SilkS")
		)
		(fp_line
			(start 0.67945 0.3048)
			(end 0.120396 0.3048)
			(stroke
				(width 0.1)
				(type default)
			)
			(layer "F.Fab")
		)
		(fp_line
			(start 0.67945 -0.3048)
			(end 0.67945 0.3048)
			(stroke
				(width 0.1)
				(type default)
			)
			(layer "F.Fab")
		)
		(fp_line
			(start 0.12065 -0.2794)
			(end 0.12065 -0.3048)
			(stroke
				(width 0.1)
				(type default)
			)
			(layer "F.Fab")
		)
		(fp_line
			(start 0.12065 -0.3048)
			(end 0.67945 -0.3048)
			(stroke
				(width 0.1)
				(type default)
			)
			(layer "F.Fab")
		)
		(fp_line
			(start 0.120396 0.3048)
			(end 0.120396 0.2794)
			(stroke
				(width 0.1)
				(type default)
			)
			(layer "F.Fab")
		)
		(fp_line
			(start 0.120396 0.2794)
			(end -0.12065 0.2794)
			(stroke
				(width 0.1)
				(type default)
			)
			(layer "F.Fab")
		)
		(fp_line
			(start -0.12065 0.3048)
			(end -0.67945 0.3048)
			(stroke
				(width 0.1)
				(type default)
			)
			(layer "F.Fab")
		)
		(fp_line
			(start -0.12065 0.2794)
			(end -0.12065 0.3048)
			(stroke
				(width 0.1)
				(type default)
			)
			(layer "F.Fab")
		)
		(fp_line
			(start -0.12065 -0.2794)
			(end 0.12065 -0.2794)
			(stroke
				(width 0.1)
				(type default)
			)
			(layer "F.Fab")
		)
		(fp_line
			(start -0.12065 -0.305054)
			(end -0.12065 -0.2794)
			(stroke
				(width 0.1)
				(type default)
			)
			(layer "F.Fab")
		)
		(fp_line
			(start -0.67945 0.3048)
			(end -0.67945 -0.305054)
			(stroke
				(width 0.1)
				(type default)
			)
			(layer "F.Fab")
		)
		(fp_line
			(start -0.67945 -0.305054)
			(end -0.12065 -0.305054)
			(stroke
				(width 0.1)
				(type default)
			)
			(layer "F.Fab")
		)
		(pad "1" smd circle
			(at -0.40005 0 180)
			(size 0 0)
			(layers "F.Cu" "F.Mask" "F.Paste")
			(net "P12V_SSD14_PG_G1")
		)
		(pad "2" smd circle
			(at 0.40005 0 180)
			(size 0 0)
			(layers "F.Cu" "F.Mask" "F.Paste")
			(net "GND")
		)
	)
	(footprint ""
		(layer "F.Cu")
		(at 212.805264 -213.348062 180)
		(property "Reference" "C4502"
			(at 0 0 180)
			(layer "F.SilkS")
			(hide yes)
			(effects
				(font
					(size 1.27 1.27)
				)
			)
		)
		(property "Value" ""
			(at 0 0 180)
			(layer "F.Fab")
			(effects
				(font
					(size 1.27 1.27)
				)
			)
		)
		(duplicate_pad_numbers_are_jumpers no)
		(fp_line
			(start 0.7874 0.4064)
			(end -0.7874 0.4064)
			(stroke
				(width 0.1524)
				(type default)
			)
			(layer "F.SilkS")
		)
		(fp_line
			(start 0.7874 -0.4064)
			(end 0.7874 0.4064)
			(stroke
				(width 0.1524)
				(type default)
			)
			(layer "F.SilkS")
		)
		(fp_line
			(start -0.7874 0.4064)
			(end -0.7874 -0.4064)
			(stroke
				(width 0.1524)
				(type default)
			)
			(layer "F.SilkS")
		)
		(fp_line
			(start -0.7874 -0.4064)
			(end 0.7874 -0.4064)
			(stroke
				(width 0.1524)
				(type default)
			)
			(layer "F.SilkS")
		)
		(fp_line
			(start 0.67945 0.3048)
			(end 0.120396 0.3048)
			(stroke
				(width 0.1)
				(type default)
			)
			(layer "F.Fab")
		)
		(fp_line
			(start 0.67945 -0.3048)
			(end 0.67945 0.3048)
			(stroke
				(width 0.1)
				(type default)
			)
			(layer "F.Fab")
		)
		(fp_line
			(start 0.12065 -0.2794)
			(end 0.12065 -0.3048)
			(stroke
				(width 0.1)
				(type default)
			)
			(layer "F.Fab")
		)
		(fp_line
			(start 0.12065 -0.3048)
			(end 0.67945 -0.3048)
			(stroke
				(width 0.1)
				(type default)
			)
			(layer "F.Fab")
		)
		(fp_line
			(start 0.120396 0.3048)
			(end 0.120396 0.2794)
			(stroke
				(width 0.1)
				(type default)
			)
			(layer "F.Fab")
		)
		(fp_line
			(start 0.120396 0.2794)
			(end -0.12065 0.2794)
			(stroke
				(width 0.1)
				(type default)
			)
			(layer "F.Fab")
		)
		(fp_line
			(start -0.12065 0.3048)
			(end -0.67945 0.3048)
			(stroke
				(width 0.1)
				(type default)
			)
			(layer "F.Fab")
		)
		(fp_line
			(start -0.12065 0.2794)
			(end -0.12065 0.3048)
			(stroke
				(width 0.1)
				(type default)
			)
			(layer "F.Fab")
		)
		(fp_line
			(start -0.12065 -0.2794)
			(end 0.12065 -0.2794)
			(stroke
				(width 0.1)
				(type default)
			)
			(layer "F.Fab")
		)
		(fp_line
			(start -0.12065 -0.305054)
			(end -0.12065 -0.2794)
			(stroke
				(width 0.1)
				(type default)
			)
			(layer "F.Fab")
		)
		(fp_line
			(start -0.67945 0.3048)
			(end -0.67945 -0.305054)
			(stroke
				(width 0.1)
				(type default)
			)
			(layer "F.Fab")
		)
		(fp_line
			(start -0.67945 -0.305054)
			(end -0.12065 -0.305054)
			(stroke
				(width 0.1)
				(type default)
			)
			(layer "F.Fab")
		)
		(pad "1" smd circle
			(at -0.40005 0 180)
			(size 0 0)
			(layers "F.Cu" "F.Mask" "F.Paste")
			(net "SMB_ALERT_PMBUS_R_N")
		)
		(pad "2" smd circle
			(at 0.40005 0 180)
			(size 0 0)
			(layers "F.Cu" "F.Mask" "F.Paste")
			(net "GND")
		)
	)
	(footprint ""
		(layer "F.Cu")
		(at 277.44674 -37.47516)
		(property "Reference" "R6098"
			(at 0 0 0)
			(layer "F.SilkS")
			(hide yes)
			(effects
				(font
					(size 1.27 1.27)
				)
			)
		)
		(property "Value" ""
			(at 0 0 0)
			(layer "F.Fab")
			(effects
				(font
					(size 1.27 1.27)
				)
			)
		)
		(duplicate_pad_numbers_are_jumpers no)
		(fp_line
			(start -0.7874 -0.4064)
			(end 0.7874 -0.4064)
			(stroke
				(width 0.1524)
				(type default)
			)
			(layer "F.SilkS")
		)
		(fp_line
			(start -0.7874 0.4064)
			(end -0.7874 -0.4064)
			(stroke
				(width 0.1524)
				(type default)
			)
			(layer "F.SilkS")
		)
		(fp_line
			(start 0.7874 -0.4064)
			(end 0.7874 0.4064)
			(stroke
				(width 0.1524)
				(type default)
			)
			(layer "F.SilkS")
		)
		(fp_line
			(start 0.7874 0.4064)
			(end -0.7874 0.4064)
			(stroke
				(width 0.1524)
				(type default)
			)
			(layer "F.SilkS")
		)
		(fp_line
			(start -0.67945 -0.305054)
			(end -0.12065 -0.305054)
			(stroke
				(width 0.1)
				(type default)
			)
			(layer "F.Fab")
		)
		(fp_line
			(start -0.67945 0.3048)
			(end -0.67945 -0.305054)
			(stroke
				(width 0.1)
				(type default)
			)
			(layer "F.Fab")
		)
		(fp_line
			(start -0.12065 -0.305054)
			(end -0.12065 -0.2794)
			(stroke
				(width 0.1)
				(type default)
			)
			(layer "F.Fab")
		)
		(fp_line
			(start -0.12065 -0.2794)
			(end 0.12065 -0.2794)
			(stroke
				(width 0.1)
				(type default)
			)
			(layer "F.Fab")
		)
		(fp_line
			(start -0.12065 0.2794)
			(end -0.12065 0.3048)
			(stroke
				(width 0.1)
				(type default)
			)
			(layer "F.Fab")
		)
		(fp_line
			(start -0.12065 0.3048)
			(end -0.67945 0.3048)
			(stroke
				(width 0.1)
				(type default)
			)
			(layer "F.Fab")
		)
		(fp_line
			(start 0.120396 0.2794)
			(end -0.12065 0.2794)
			(stroke
				(width 0.1)
				(type default)
			)
			(layer "F.Fab")
		)
		(fp_line
			(start 0.120396 0.3048)
			(end 0.120396 0.2794)
			(stroke
				(width 0.1)
				(type default)
			)
			(layer "F.Fab")
		)
		(fp_line
			(start 0.12065 -0.3048)
			(end 0.67945 -0.3048)
			(stroke
				(width 0.1)
				(type default)
			)
			(layer "F.Fab")
		)
		(fp_line
			(start 0.12065 -0.2794)
			(end 0.12065 -0.3048)
			(stroke
				(width 0.1)
				(type default)
			)
			(layer "F.Fab")
		)
		(fp_line
			(start 0.67945 -0.3048)
			(end 0.67945 0.3048)
			(stroke
				(width 0.1)
				(type default)
			)
			(layer "F.Fab")
		)
		(fp_line
			(start 0.67945 0.3048)
			(end 0.120396 0.3048)
			(stroke
				(width 0.1)
				(type default)
			)
			(layer "F.Fab")
		)
		(pad "1" smd circle
			(at -0.40005 0)
			(size 0 0)
			(layers "F.Cu" "F.Mask" "F.Paste")
			(net "P3V3_SSD10")
		)
		(pad "2" smd circle
			(at 0.40005 0)
			(size 0 0)
			(layers "F.Cu" "F.Mask" "F.Paste")
			(net "P3V3_SSD10_PG_G1")
		)
	)
	(footprint ""
		(layer "F.Cu")
		(at 385.440174 -85.811614)
		(property "Reference" "U142"
			(at -1.950974 -4.763516 0)
			(unlocked yes)
			(layer "F.SilkS")
			(effects
				(font
					(size 0.7874 0.5842)
					(thickness 0.1524)
				)
				(justify left)
			)
		)
		(property "Value" ""
			(at 0 0 0)
			(layer "F.Fab")
			(effects
				(font
					(size 1.27 1.27)
				)
			)
		)
		(duplicate_pad_numbers_are_jumpers no)
		(fp_line
			(start -1.8542 -3.949954)
			(end -1.8542 3.949954)
			(stroke
				(width 0.1524)
				(type default)
			)
			(layer "F.SilkS")
		)
		(fp_line
			(start -1.8542 3.949954)
			(end 1.8542 3.949954)
			(stroke
				(width 0.1524)
				(type default)
			)
			(layer "F.SilkS")
		)
		(fp_line
			(start -1.282954 -3.949954)
			(end -1.8542 -3.949954)
			(stroke
				(width 0.1524)
				(type default)
			)
			(layer "F.SilkS")
		)
		(fp_line
			(start 0 -2.667)
			(end -1.282954 -3.949954)
			(stroke
				(width 0.1524)
				(type default)
			)
			(layer "F.SilkS")
		)
		(fp_line
			(start 1.282954 -3.949954)
			(end 0 -2.667)
			(stroke
				(width 0.1524)
				(type default)
			)
			(layer "F.SilkS")
		)
		(fp_line
			(start 1.8542 -3.949954)
			(end 1.282954 -3.949954)
			(stroke
				(width 0.1524)
				(type default)
			)
			(layer "F.SilkS")
		)
		(fp_line
			(start 1.8542 3.949954)
			(end 1.8542 -3.949954)
			(stroke
				(width 0.1524)
				(type default)
			)
			(layer "F.SilkS")
		)
		(fp_poly
			(pts
				(xy -4.8006 -4.08305) (xy -4.8006 -3.06705) (xy -3.7846 -3.57505)
			)
			(stroke
				(width 0)
				(type default)
			)
			(fill yes)
			(layer "F.SilkS")
		)
		(fp_line
			(start -2.249932 -3.949954)
			(end -2.249932 3.949954)
			(stroke
				(width 0.1)
				(type default)
			)
			(layer "F.Fab")
		)
		(fp_line
			(start -2.249932 3.949954)
			(end 2.249932 3.949954)
			(stroke
				(width 0.1)
				(type default)
			)
			(layer "F.Fab")
		)
		(fp_line
			(start 2.249932 -3.949954)
			(end -2.249932 -3.949954)
			(stroke
				(width 0.1)
				(type default)
			)
			(layer "F.Fab")
		)
		(fp_line
			(start 2.249932 3.949954)
			(end 2.249932 -3.949954)
			(stroke
				(width 0.1)
				(type default)
			)
			(layer "F.Fab")
		)
		(fp_poly
			(pts
				(xy -4.8006 -4.08305) (xy -4.8006 -3.06705) (xy -3.7846 -3.57505)
			)
			(stroke
				(width 0)
				(type default)
			)
			(fill yes)
			(layer "F.Fab")
		)
		(pad "1" smd rect
			(at -2.800096 -3.57505 270)
			(size 0.3048 1.6002)
			(layers "F.Cu" "F.Mask" "F.Paste")
			(net "BIC_I2C6_MUX_A0")
		)
		(pad "2" smd rect
			(at -2.800096 -2.925064 270)
			(size 0.3048 1.6002)
			(layers "F.Cu" "F.Mask" "F.Paste")
			(net "BIC_I2C6_MUX_A1")
		)
		(pad "3" smd rect
			(at -2.800096 -2.275078 270)
			(size 0.3048 1.6002)
			(layers "F.Cu" "F.Mask" "F.Paste")
			(net "RST_BIC_I2C6_MUX_R_N")
		)
		(pad "4" smd rect
			(at -2.800096 -1.625092 270)
			(size 0.3048 1.6002)
			(layers "F.Cu" "F.Mask" "F.Paste")
			(net "SMB_BIC_I2C6_MUX_NIC_ADC_SDA")
		)
		(pad "5" smd rect
			(at -2.800096 -0.975106 270)
			(size 0.3048 1.6002)
			(layers "F.Cu" "F.Mask" "F.Paste")
			(net "SMB_BIC_I2C6_MUX_NIC_ADC_SCL")
		)
		(pad "6" smd rect
			(at -2.800096 -0.32512 270)
			(size 0.3048 1.6002)
			(layers "F.Cu" "F.Mask" "F.Paste")
			(net "SMB_BIC_I2C6_MUX_PEX_ADC_SDA")
		)
		(pad "7" smd rect
			(at -2.800096 0.32512 270)
			(size 0.3048 1.6002)
			(layers "F.Cu" "F.Mask" "F.Paste")
			(net "SMB_BIC_I2C6_MUX_PEX_ADC_SCL")
		)
		(pad "8" smd rect
			(at -2.800096 0.975106 270)
			(size 0.3048 1.6002)
			(layers "F.Cu" "F.Mask" "F.Paste")
			(net "SMB_BIC_I2C6_MUX_THERMAL_SDA")
		)
		(pad "9" smd rect
			(at -2.800096 1.625092 270)
			(size 0.3048 1.6002)
			(layers "F.Cu" "F.Mask" "F.Paste")
			(net "SMB_BIC_I2C6_MUX_THERMAL_SCL")
		)
		(pad "10" smd rect
			(at -2.800096 2.275078 270)
			(size 0.3048 1.6002)
			(layers "F.Cu" "F.Mask" "F.Paste")
			(net "SMB_BIC_I2C6_MUX_SSD_0_7_ADC_SDA")
		)
		(pad "11" smd rect
			(at -2.800096 2.925064 270)
			(size 0.3048 1.6002)
			(layers "F.Cu" "F.Mask" "F.Paste")
			(net "SMB_BIC_I2C6_MUX_SSD_0_7_ADC_SCL")
		)
		(pad "12" smd rect
			(at -2.800096 3.57505 270)
			(size 0.3048 1.6002)
			(layers "F.Cu" "F.Mask" "F.Paste")
			(net "GND")
		)
		(pad "13" smd rect
			(at 2.800096 3.57505 270)
			(size 0.3048 1.6002)
			(layers "F.Cu" "F.Mask" "F.Paste")
			(net "SMB_BIC_I2C6_MUX_SSD_8_15_ADC_SDA")
		)
		(pad "14" smd rect
			(at 2.800096 2.925064 270)
			(size 0.3048 1.6002)
			(layers "F.Cu" "F.Mask" "F.Paste")
			(net "SMB_BIC_I2C6_MUX_SSD_8_15_ADC_SCL")
		)
		(pad "15" smd rect
			(at 2.800096 2.275078 270)
			(size 0.3048 1.6002)
			(layers "F.Cu" "F.Mask" "F.Paste")
			(net "SMB_BIC_I2C6_MUX_CLK_SDA")
		)
		(pad "16" smd rect
			(at 2.800096 1.625092 270)
			(size 0.3048 1.6002)
			(layers "F.Cu" "F.Mask" "F.Paste")
			(net "SMB_BIC_I2C6_MUX_CLK_SCL")
		)
		(pad "17" smd rect
			(at 2.800096 0.975106 270)
			(size 0.3048 1.6002)
			(layers "F.Cu" "F.Mask" "F.Paste")
			(net "SMB_BIC_I2C6_MUX_VR_SDA")
		)
		(pad "18" smd rect
			(at 2.800096 0.32512 270)
			(size 0.3048 1.6002)
			(layers "F.Cu" "F.Mask" "F.Paste")
			(net "SMB_BIC_I2C6_MUX_VR_SCL")
		)
		(pad "19" smd rect
			(at 2.800096 -0.32512 270)
			(size 0.3048 1.6002)
			(layers "F.Cu" "F.Mask" "F.Paste")
			(net "SMB_BIC_I2C6_MUX_FRU_SDA")
		)
		(pad "20" smd rect
			(at 2.800096 -0.975106 270)
			(size 0.3048 1.6002)
			(layers "F.Cu" "F.Mask" "F.Paste")
			(net "SMB_BIC_I2C6_MUX_FRU_SCL")
		)
		(pad "21" smd rect
			(at 2.800096 -1.625092 270)
			(size 0.3048 1.6002)
			(layers "F.Cu" "F.Mask" "F.Paste")
			(net "BIC_I2C6_MUX_A2")
		)
		(pad "22" smd rect
			(at 2.800096 -2.275078 270)
			(size 0.3048 1.6002)
			(layers "F.Cu" "F.Mask" "F.Paste")
			(net "SMB_BIC_I2C6_SENEOR_SCL")
		)
		(pad "23" smd rect
			(at 2.800096 -2.925064 270)
			(size 0.3048 1.6002)
			(layers "F.Cu" "F.Mask" "F.Paste")
			(net "SMB_BIC_I2C6_SENEOR_SDA")
		)
		(pad "24" smd rect
			(at 2.800096 -3.57505 270)
			(size 0.3048 1.6002)
			(layers "F.Cu" "F.Mask" "F.Paste")
			(net "P3V3_AUX")
		)
	)
	(footprint ""
		(layer "F.Cu")
		(at 196.119242 -146.190208 180)
		(property "Reference" "C223"
			(at 0 0 180)
			(layer "F.SilkS")
			(hide yes)
			(effects
				(font
					(size 1.27 1.27)
				)
			)
		)
		(property "Value" ""
			(at 0 0 180)
			(layer "F.Fab")
			(effects
				(font
					(size 1.27 1.27)
				)
			)
		)
		(duplicate_pad_numbers_are_jumpers no)
		(fp_line
			(start 0.299974 0.150114)
			(end -0.299974 0.150114)
			(stroke
				(width 0.1)
				(type default)
			)
			(layer "F.Fab")
		)
		(fp_line
			(start 0.299974 -0.150114)
			(end 0.299974 0.150114)
			(stroke
				(width 0.1)
				(type default)
			)
			(layer "F.Fab")
		)
		(fp_line
			(start -0.299974 0.150114)
			(end -0.299974 -0.150114)
			(stroke
				(width 0.1)
				(type default)
			)
			(layer "F.Fab")
		)
		(fp_line
			(start -0.299974 -0.150114)
			(end 0.299974 -0.150114)
			(stroke
				(width 0.1)
				(type default)
			)
			(layer "F.Fab")
		)
		(pad "1" smd rect
			(at -0.2667 0 180)
			(size 0.3048 0.381)
			(layers "F.Cu" "F.Mask" "F.Paste")
			(net "P5E_PEX1_STN0_TX_DN<10>")
		)
		(pad "2" smd rect
			(at 0.2667 0 180)
			(size 0.3048 0.381)
			(layers "F.Cu" "F.Mask" "F.Paste")
			(net "P5E_PEX1_STN0_TX_C_DN<10>")
		)
	)
)
